(kicad_pcb
	(version 20260206)
	(generator "pcbnew")
	(generator_version "10.0")
	(general
		(thickness 1.6)
		(legacy_teardrops no)
	)
	(paper "A4")
	(title_block
		(title "Bryce Canyon_IOM_M2_16342-2_OCP.brd")
		(comment 1 "Bryce Canyon / footprints 748-751 of 1146")
	)
	(layers
		(0 "F.Cu" signal "TOP")
		(4 "In1.Cu" signal "L2GND")
		(6 "In2.Cu" signal "L3")
		(8 "In3.Cu" signal "L4VCC")
		(10 "In4.Cu" signal "L5VCC")
		(12 "In5.Cu" signal "L6")
		(14 "In6.Cu" signal "L7GND")
		(2 "B.Cu" signal "BOTTOM")
		(9 "F.Adhes" user "F.Adhesive")
		(11 "B.Adhes" user "B.Adhesive")
		(13 "F.Paste" user "Package Geometry/Pastemask Top")
		(15 "B.Paste" user "Package Geometry/Pastemask Bottom")
		(5 "F.SilkS" user "Ref Des/Silkscreen Top")
		(7 "B.SilkS" user "Ref Des/Silkscreen Bottom")
		(1 "F.Mask" user "Board Geometry/Soldermask Top")
		(3 "B.Mask" user "Board Geometry/Soldermask Bottom")
		(17 "Dwgs.User" user "User.Drawings")
		(19 "Cmts.User" user "User.Comments")
		(21 "Eco1.User" user "User.Eco1")
		(23 "Eco2.User" user "User.Eco2")
		(25 "Edge.Cuts" user "Board Geometry/Outline")
		(27 "Margin" user)
		(31 "F.CrtYd" user "Package Geometry/Place Bound Top")
		(29 "B.CrtYd" user "Package Geometry/Place Bound Bottom")
		(35 "F.Fab" user "Ref Des/Assembly Top")
		(33 "B.Fab" user "Ref Des/Assembly Bottom")
	)
	(footprint ""
		(layer "B.Cu")
		(at 57.42305 -146.511264 -90)
		(property "Reference" "R360"
			(at 0 0 90)
			(layer "B.SilkS")
			(hide yes)
			(effects
				(font
					(size 1.27 1.27)
				)
				(justify mirror)
			)
		)
		(property "Value" "10KR2F-2-GP"
			(at -0.064008 -3.993896 270)
			(unlocked yes)
			(layer "B.Fab")
			(hide yes)
			(effects
				(font
					(size 1.016 1.016)
					(thickness 0.1524)
				)
				(justify mirror)
			)
		)
		(property "Device Type" "R402H16"
			(at -0.064008 -5.517896 270)
			(unlocked yes)
			(layer "B.Fab")
			(hide yes)
			(effects
				(font
					(size 1.016 1.016)
					(thickness 0.1524)
				)
				(justify mirror)
			)
		)
		(duplicate_pad_numbers_are_jumpers no)
		(fp_line
			(start -0.508 -0.9398)
			(end 0.508 -0.9398)
			(stroke
				(width 0.1524)
				(type default)
			)
			(layer "B.SilkS")
		)
		(fp_line
			(start 0.508 -0.9398)
			(end 0.508 0.9398)
			(stroke
				(width 0.1524)
				(type default)
			)
			(layer "B.SilkS")
		)
		(fp_rect
			(start 0.508 0.9398)
			(end -0.508 -0.9398)
			(stroke
				(width 0)
				(type default)
			)
			(fill no)
			(layer "B.CrtYd")
		)
		(fp_rect
			(start 0.508 0.9398)
			(end -0.508 -0.9398)
			(stroke
				(width 0)
				(type default)
			)
			(fill no)
			(layer "B.Fab")
		)
		(pad "1" smd custom
			(at 0 -0.4445 90)
			(size 0.1397 0.1397)
			(layers "B.Cu" "B.Mask" "B.Paste")
			(net "P3V3_STBY")
			(options
				(clearance outline)
				(anchor circle)
			)
			(primitives
				(gr_poly
					(pts
						(arc
							(start -0.1778 0.2794)
							(mid -0.249642 0.249642)
							(end -0.2794 0.1778)
						)
						(arc
							(start -0.2794 -0.1778)
							(mid -0.249642 -0.249642)
							(end -0.1778 -0.2794)
						)
						(arc
							(start 0.1778 -0.2794)
							(mid 0.249642 -0.249642)
							(end 0.2794 -0.1778)
						)
						(arc
							(start 0.2794 0.1778)
							(mid 0.249642 0.249642)
							(end 0.1778 0.2794)
						)
					)
					(width 0)
					(fill yes)
				)
			)
		)
		(pad "2" smd custom
			(at 0 0.4445 90)
			(size 0.1397 0.1397)
			(layers "B.Cu" "B.Mask" "B.Paste")
			(net "JTAG_BMC_TCK")
			(options
				(clearance outline)
				(anchor circle)
			)
			(primitives
				(gr_poly
					(pts
						(arc
							(start -0.1778 0.2794)
							(mid -0.249642 0.249642)
							(end -0.2794 0.1778)
						)
						(arc
							(start -0.2794 -0.1778)
							(mid -0.249642 -0.249642)
							(end -0.1778 -0.2794)
						)
						(arc
							(start 0.1778 -0.2794)
							(mid 0.249642 -0.249642)
							(end 0.2794 -0.1778)
						)
						(arc
							(start 0.2794 0.1778)
							(mid 0.249642 0.249642)
							(end 0.1778 0.2794)
						)
					)
					(width 0)
					(fill yes)
				)
			)
		)
	)
	(footprint ""
		(layer "B.Cu")
		(at 215.60028 -102.050088)
		(property "Reference" "R844"
			(at 0 0 0)
			(layer "B.SilkS")
			(hide yes)
			(effects
				(font
					(size 1.27 1.27)
				)
				(justify mirror)
			)
		)
		(property "Value" "309KR2F-GP"
			(at -0.064008 -3.993896 0)
			(unlocked yes)
			(layer "B.Fab")
			(hide yes)
			(effects
				(font
					(size 1.016 1.016)
					(thickness 0.1524)
				)
				(justify mirror)
			)
		)
		(property "Device Type" "R402H16"
			(at -0.064008 -5.517896 0)
			(unlocked yes)
			(layer "B.Fab")
			(hide yes)
			(effects
				(font
					(size 1.016 1.016)
					(thickness 0.1524)
				)
				(justify mirror)
			)
		)
		(duplicate_pad_numbers_are_jumpers no)
		(fp_line
			(start -0.508 -0.9398)
			(end 0.508 -0.9398)
			(stroke
				(width 0.1524)
				(type default)
			)
			(layer "B.SilkS")
		)
		(fp_line
			(start 0.508 -0.9398)
			(end 0.508 0.9398)
			(stroke
				(width 0.1524)
				(type default)
			)
			(layer "B.SilkS")
		)
		(fp_rect
			(start 0.508 0.9398)
			(end -0.508 -0.9398)
			(stroke
				(width 0)
				(type default)
			)
			(fill no)
			(layer "B.CrtYd")
		)
		(fp_rect
			(start 0.508 0.9398)
			(end -0.508 -0.9398)
			(stroke
				(width 0)
				(type default)
			)
			(fill no)
			(layer "B.Fab")
		)
		(pad "1" smd custom
			(at 0 -0.4445 180)
			(size 0.1397 0.1397)
			(layers "B.Cu" "B.Mask" "B.Paste")
			(net "P3V3_M2_VREG")
			(options
				(clearance outline)
				(anchor circle)
			)
			(primitives
				(gr_poly
					(pts
						(arc
							(start -0.1778 0.2794)
							(mid -0.249642 0.249642)
							(end -0.2794 0.1778)
						)
						(arc
							(start -0.2794 -0.1778)
							(mid -0.249642 -0.249642)
							(end -0.1778 -0.2794)
						)
						(arc
							(start 0.1778 -0.2794)
							(mid 0.249642 -0.249642)
							(end 0.2794 -0.1778)
						)
						(arc
							(start 0.2794 0.1778)
							(mid 0.249642 0.249642)
							(end 0.1778 0.2794)
						)
					)
					(width 0)
					(fill yes)
				)
			)
		)
		(pad "2" smd custom
			(at 0 0.4445 180)
			(size 0.1397 0.1397)
			(layers "B.Cu" "B.Mask" "B.Paste")
			(net "P3V3_M2_RF")
			(options
				(clearance outline)
				(anchor circle)
			)
			(primitives
				(gr_poly
					(pts
						(arc
							(start -0.1778 0.2794)
							(mid -0.249642 0.249642)
							(end -0.2794 0.1778)
						)
						(arc
							(start -0.2794 -0.1778)
							(mid -0.249642 -0.249642)
							(end -0.1778 -0.2794)
						)
						(arc
							(start 0.1778 -0.2794)
							(mid 0.249642 -0.249642)
							(end 0.2794 -0.1778)
						)
						(arc
							(start 0.2794 0.1778)
							(mid 0.249642 0.249642)
							(end 0.1778 0.2794)
						)
					)
					(width 0)
					(fill yes)
				)
			)
		)
	)
	(footprint ""
		(layer "B.Cu")
		(at 87.3506 -95.9612 -90)
		(property "Reference" "R728"
			(at 0 0 90)
			(layer "B.SilkS")
			(hide yes)
			(effects
				(font
					(size 1.27 1.27)
				)
				(justify mirror)
			)
		)
		(property "Value" "4K7R2F-GP"
			(at -0.064008 -3.993896 270)
			(unlocked yes)
			(layer "B.Fab")
			(hide yes)
			(effects
				(font
					(size 1.016 1.016)
					(thickness 0.1524)
				)
				(justify mirror)
			)
		)
		(property "Device Type" "R402H16"
			(at -0.064008 -5.517896 270)
			(unlocked yes)
			(layer "B.Fab")
			(hide yes)
			(effects
				(font
					(size 1.016 1.016)
					(thickness 0.1524)
				)
				(justify mirror)
			)
		)
		(duplicate_pad_numbers_are_jumpers no)
		(fp_line
			(start -0.508 -0.9398)
			(end 0.508 -0.9398)
			(stroke
				(width 0.1524)
				(type default)
			)
			(layer "B.SilkS")
		)
		(fp_line
			(start 0.508 -0.9398)
			(end 0.508 0.9398)
			(stroke
				(width 0.1524)
				(type default)
			)
			(layer "B.SilkS")
		)
		(fp_rect
			(start 0.508 0.9398)
			(end -0.508 -0.9398)
			(stroke
				(width 0)
				(type default)
			)
			(fill no)
			(layer "B.CrtYd")
		)
		(fp_rect
			(start 0.508 0.9398)
			(end -0.508 -0.9398)
			(stroke
				(width 0)
				(type default)
			)
			(fill no)
			(layer "B.Fab")
		)
		(pad "1" smd custom
			(at 0 -0.4445 90)
			(size 0.1397 0.1397)
			(layers "B.Cu" "B.Mask" "B.Paste")
			(net "CONN_A_PRSNTA")
			(options
				(clearance outline)
				(anchor circle)
			)
			(primitives
				(gr_poly
					(pts
						(arc
							(start -0.1778 0.2794)
							(mid -0.249642 0.249642)
							(end -0.2794 0.1778)
						)
						(arc
							(start -0.2794 -0.1778)
							(mid -0.249642 -0.249642)
							(end -0.1778 -0.2794)
						)
						(arc
							(start 0.1778 -0.2794)
							(mid 0.249642 -0.249642)
							(end 0.2794 -0.1778)
						)
						(arc
							(start 0.2794 0.1778)
							(mid 0.249642 0.249642)
							(end 0.1778 0.2794)
						)
					)
					(width 0)
					(fill yes)
				)
			)
		)
		(pad "2" smd custom
			(at 0 0.4445 90)
			(size 0.1397 0.1397)
			(layers "B.Cu" "B.Mask" "B.Paste")
			(net "P3V3_STBY")
			(options
				(clearance outline)
				(anchor circle)
			)
			(primitives
				(gr_poly
					(pts
						(arc
							(start -0.1778 0.2794)
							(mid -0.249642 0.249642)
							(end -0.2794 0.1778)
						)
						(arc
							(start -0.2794 -0.1778)
							(mid -0.249642 -0.249642)
							(end -0.1778 -0.2794)
						)
						(arc
							(start 0.1778 -0.2794)
							(mid 0.249642 -0.249642)
							(end 0.2794 -0.1778)
						)
						(arc
							(start 0.2794 0.1778)
							(mid 0.249642 0.249642)
							(end 0.1778 0.2794)
						)
					)
					(width 0)
					(fill yes)
				)
			)
		)
	)
	(footprint ""
		(layer "B.Cu")
		(at 40.2844 -133.7818 180)
		(property "Reference" "R375"
			(at 0 0 0)
			(layer "B.SilkS")
			(hide yes)
			(effects
				(font
					(size 1.27 1.27)
				)
				(justify mirror)
			)
		)
		(property "Value" "4K7R2F-GP"
			(at -0.064008 -3.993896 180)
			(unlocked yes)
			(layer "B.Fab")
			(hide yes)
			(effects
				(font
					(size 1.016 1.016)
					(thickness 0.1524)
				)
				(justify mirror)
			)
		)
		(property "Device Type" "R402H16"
			(at -0.064008 -5.517896 180)
			(unlocked yes)
			(layer "B.Fab")
			(hide yes)
			(effects
				(font
					(size 1.016 1.016)
					(thickness 0.1524)
				)
				(justify mirror)
			)
		)
		(duplicate_pad_numbers_are_jumpers no)
		(fp_line
			(start 0.508 -0.9398)
			(end 0.508 0.9398)
			(stroke
				(width 0.1524)
				(type default)
			)
			(layer "B.SilkS")
		)
		(fp_line
			(start -0.508 -0.9398)
			(end 0.508 -0.9398)
			(stroke
				(width 0.1524)
				(type default)
			)
			(layer "B.SilkS")
		)
		(fp_rect
			(start 0.508 0.9398)
			(end -0.508 -0.9398)
			(stroke
				(width 0)
				(type default)
			)
			(fill no)
			(layer "B.CrtYd")
		)
		(fp_rect
			(start 0.508 0.9398)
			(end -0.508 -0.9398)
			(stroke
				(width 0)
				(type default)
			)
			(fill no)
			(layer "B.Fab")
		)
		(pad "1" smd custom
			(at 0 -0.4445)
			(size 0.1397 0.1397)
			(layers "B.Cu" "B.Mask" "B.Paste")
			(net "P3V3_STBY")
			(options
				(clearance outline)
				(anchor circle)
			)
			(primitives
				(gr_poly
					(pts
						(arc
							(start -0.1778 0.2794)
							(mid -0.249642 0.249642)
							(end -0.2794 0.1778)
						)
						(arc
							(start -0.2794 -0.1778)
							(mid -0.249642 -0.249642)
							(end -0.1778 -0.2794)
						)
						(arc
							(start 0.1778 -0.2794)
							(mid 0.249642 -0.249642)
							(end 0.2794 -0.1778)
						)
						(arc
							(start 0.2794 0.1778)
							(mid 0.249642 0.249642)
							(end 0.1778 0.2794)
						)
					)
					(width 0)
					(fill yes)
				)
			)
		)
		(pad "2" smd custom
			(at 0 0.4445)
			(size 0.1397 0.1397)
			(layers "B.Cu" "B.Mask" "B.Paste")
			(net "BMC_GPIOS7")
			(options
				(clearance outline)
				(anchor circle)
			)
			(primitives
				(gr_poly
					(pts
						(arc
							(start -0.1778 0.2794)
							(mid -0.249642 0.249642)
							(end -0.2794 0.1778)
						)
						(arc
							(start -0.2794 -0.1778)
							(mid -0.249642 -0.249642)
							(end -0.1778 -0.2794)
						)
						(arc
							(start 0.1778 -0.2794)
							(mid 0.249642 -0.249642)
							(end 0.2794 -0.1778)
						)
						(arc
							(start 0.2794 0.1778)
							(mid 0.249642 0.249642)
							(end 0.1778 0.2794)
						)
					)
					(width 0)
					(fill yes)
				)
			)
		)
	)
)
